(kicad_pcb
	(version 20260206)
	(generator "pcbnew")
	(generator_version "10.0")
	(general
		(thickness 1.6)
		(legacy_teardrops no)
	)
	(paper "A4")
	(title_block
		(title "Bryce Canyon_F.DPB_16315-1-OCP.brd")
		(comment 1 "Bryce Canyon / footprints 739-745 of 2223")
	)
	(layers
		(0 "F.Cu" signal "TOP")
		(4 "In1.Cu" signal "L2GND")
		(6 "In2.Cu" signal "L3")
		(8 "In3.Cu" signal "L4GND")
		(10 "In4.Cu" signal "L5")
		(12 "In5.Cu" signal "L6VCC")
		(14 "In6.Cu" signal "L7VCC")
		(16 "In7.Cu" signal "L8")
		(18 "In8.Cu" signal "L9GND")
		(20 "In9.Cu" signal "L10")
		(22 "In10.Cu" signal "L11GND")
		(2 "B.Cu" signal "BOTTOM")
		(9 "F.Adhes" user "F.Adhesive")
		(11 "B.Adhes" user "B.Adhesive")
		(13 "F.Paste" user "Package Geometry/Pastemask Top")
		(15 "B.Paste" user "Package Geometry/Pastemask Bottom")
		(5 "F.SilkS" user "Ref Des/Silkscreen Top")
		(7 "B.SilkS" user "Ref Des/Silkscreen Bottom")
		(1 "F.Mask" user "Board Geometry/Soldermask Top")
		(3 "B.Mask" user "Board Geometry/Soldermask Bottom")
		(17 "Dwgs.User" user "User.Drawings")
		(19 "Cmts.User" user "User.Comments")
		(21 "Eco1.User" user "User.Eco1")
		(23 "Eco2.User" user "User.Eco2")
		(25 "Edge.Cuts" user "Board Geometry/Outline")
		(27 "Margin" user)
		(31 "F.CrtYd" user "Package Geometry/Place Bound Top")
		(29 "B.CrtYd" user "Package Geometry/Place Bound Bottom")
		(35 "F.Fab" user "Ref Des/Assembly Top")
		(33 "B.Fab" user "Ref Des/Assembly Bottom")
	)
	(footprint ""
		(layer "F.Cu")
		(at 381.6096 -139.4841 180)
		(property "Reference" "R1008"
			(at 0 0 180)
			(layer "F.SilkS")
			(hide yes)
			(effects
				(font
					(size 1.27 1.27)
				)
			)
		)
		(property "Value" "100KR2F-L1-GP"
			(at 0.064008 -3.993896 180)
			(unlocked yes)
			(layer "F.Fab")
			(hide yes)
			(effects
				(font
					(size 1.016 1.016)
					(thickness 0.1524)
				)
			)
		)
		(property "Device Type" "R402H16"
			(at 0.064008 -5.517896 180)
			(unlocked yes)
			(layer "F.Fab")
			(hide yes)
			(effects
				(font
					(size 1.016 1.016)
					(thickness 0.1524)
				)
			)
		)
		(duplicate_pad_numbers_are_jumpers no)
		(fp_line
			(start 0.508 -0.9398)
			(end -0.508 -0.9398)
			(stroke
				(width 0.1524)
				(type default)
			)
			(layer "F.SilkS")
		)
		(fp_line
			(start -0.508 -0.9398)
			(end -0.508 0.9398)
			(stroke
				(width 0.1524)
				(type default)
			)
			(layer "F.SilkS")
		)
		(fp_rect
			(start -0.508 0.9398)
			(end 0.508 -0.9398)
			(stroke
				(width 0)
				(type default)
			)
			(fill no)
			(layer "F.CrtYd")
		)
		(fp_rect
			(start -0.508 0.9398)
			(end 0.508 -0.9398)
			(stroke
				(width 0)
				(type default)
			)
			(fill no)
			(layer "F.Fab")
		)
		(pad "1" smd custom
			(at 0 -0.4445 180)
			(size 0.1397 0.1397)
			(layers "F.Cu" "F.Mask" "F.Paste")
			(net "COMP_B_PWR_EN")
			(options
				(clearance outline)
				(anchor circle)
			)
			(primitives
				(gr_poly
					(pts
						(arc
							(start -0.1778 -0.2794)
							(mid -0.249642 -0.249642)
							(end -0.2794 -0.1778)
						)
						(arc
							(start -0.2794 0.1778)
							(mid -0.249642 0.249642)
							(end -0.1778 0.2794)
						)
						(arc
							(start 0.1778 0.2794)
							(mid 0.249642 0.249642)
							(end 0.2794 0.1778)
						)
						(arc
							(start 0.2794 -0.1778)
							(mid 0.249642 -0.249642)
							(end 0.1778 -0.2794)
						)
					)
					(width 0)
					(fill yes)
				)
			)
		)
		(pad "2" smd custom
			(at 0 0.4445 180)
			(size 0.1397 0.1397)
			(layers "F.Cu" "F.Mask" "F.Paste")
			(net "GND")
			(options
				(clearance outline)
				(anchor circle)
			)
			(primitives
				(gr_poly
					(pts
						(arc
							(start -0.1778 -0.2794)
							(mid -0.249642 -0.249642)
							(end -0.2794 -0.1778)
						)
						(arc
							(start -0.2794 0.1778)
							(mid -0.249642 0.249642)
							(end -0.1778 0.2794)
						)
						(arc
							(start 0.1778 0.2794)
							(mid 0.249642 0.249642)
							(end 0.2794 0.1778)
						)
						(arc
							(start 0.2794 -0.1778)
							(mid 0.249642 -0.249642)
							(end 0.1778 -0.2794)
						)
					)
					(width 0)
					(fill yes)
				)
			)
		)
	)
	(footprint ""
		(layer "F.Cu")
		(at 463.1309 -275.735542 180)
		(property "Reference" "R374"
			(at 0 0 180)
			(layer "F.SilkS")
			(hide yes)
			(effects
				(font
					(size 1.27 1.27)
				)
			)
		)
		(property "Value" "4K7R2J-2-GP"
			(at 0.064008 -3.993896 180)
			(unlocked yes)
			(layer "F.Fab")
			(hide yes)
			(effects
				(font
					(size 1.016 1.016)
					(thickness 0.1524)
				)
			)
		)
		(property "Device Type" "R402H16"
			(at 0.064008 -5.517896 180)
			(unlocked yes)
			(layer "F.Fab")
			(hide yes)
			(effects
				(font
					(size 1.016 1.016)
					(thickness 0.1524)
				)
			)
		)
		(duplicate_pad_numbers_are_jumpers no)
		(fp_line
			(start 0.508 -0.9398)
			(end -0.508 -0.9398)
			(stroke
				(width 0.1524)
				(type default)
			)
			(layer "F.SilkS")
		)
		(fp_line
			(start -0.508 -0.9398)
			(end -0.508 0.9398)
			(stroke
				(width 0.1524)
				(type default)
			)
			(layer "F.SilkS")
		)
		(fp_rect
			(start -0.508 0.9398)
			(end 0.508 -0.9398)
			(stroke
				(width 0)
				(type default)
			)
			(fill no)
			(layer "F.CrtYd")
		)
		(fp_rect
			(start -0.508 0.9398)
			(end 0.508 -0.9398)
			(stroke
				(width 0)
				(type default)
			)
			(fill no)
			(layer "F.Fab")
		)
		(pad "1" smd custom
			(at 0 -0.4445 180)
			(size 0.1397 0.1397)
			(layers "F.Cu" "F.Mask" "F.Paste")
			(net "P12V_A")
			(options
				(clearance outline)
				(anchor circle)
			)
			(primitives
				(gr_poly
					(pts
						(arc
							(start -0.1778 -0.2794)
							(mid -0.249642 -0.249642)
							(end -0.2794 -0.1778)
						)
						(arc
							(start -0.2794 0.1778)
							(mid -0.249642 0.249642)
							(end -0.1778 0.2794)
						)
						(arc
							(start 0.1778 0.2794)
							(mid 0.249642 0.249642)
							(end 0.2794 0.1778)
						)
						(arc
							(start 0.2794 -0.1778)
							(mid 0.249642 -0.249642)
							(end 0.1778 -0.2794)
						)
					)
					(width 0)
					(fill yes)
				)
			)
		)
		(pad "2" smd custom
			(at 0 0.4445 180)
			(size 0.1397 0.1397)
			(layers "F.Cu" "F.Mask" "F.Paste")
			(net "SW_HDD_R10")
			(options
				(clearance outline)
				(anchor circle)
			)
			(primitives
				(gr_poly
					(pts
						(arc
							(start -0.1778 -0.2794)
							(mid -0.249642 -0.249642)
							(end -0.2794 -0.1778)
						)
						(arc
							(start -0.2794 0.1778)
							(mid -0.249642 0.249642)
							(end -0.1778 0.2794)
						)
						(arc
							(start 0.1778 0.2794)
							(mid 0.249642 0.249642)
							(end 0.2794 0.1778)
						)
						(arc
							(start 0.2794 -0.1778)
							(mid 0.249642 -0.249642)
							(end 0.1778 -0.2794)
						)
					)
					(width 0)
					(fill yes)
				)
			)
		)
	)
	(footprint ""
		(layer "F.Cu")
		(at 226.8347 -377.0122 180)
		(property "Reference" "R174"
			(at 0 0 180)
			(layer "F.SilkS")
			(hide yes)
			(effects
				(font
					(size 1.27 1.27)
				)
			)
		)
		(property "Value" "4K7R2F-GP"
			(at 0.064008 -3.993896 180)
			(unlocked yes)
			(layer "F.Fab")
			(hide yes)
			(effects
				(font
					(size 1.016 1.016)
					(thickness 0.1524)
				)
			)
		)
		(property "Device Type" "R402H16"
			(at 0.064008 -5.517896 180)
			(unlocked yes)
			(layer "F.Fab")
			(hide yes)
			(effects
				(font
					(size 1.016 1.016)
					(thickness 0.1524)
				)
			)
		)
		(duplicate_pad_numbers_are_jumpers no)
		(fp_line
			(start 0.508 -0.9398)
			(end -0.508 -0.9398)
			(stroke
				(width 0.1524)
				(type default)
			)
			(layer "F.SilkS")
		)
		(fp_line
			(start -0.508 -0.9398)
			(end -0.508 0.9398)
			(stroke
				(width 0.1524)
				(type default)
			)
			(layer "F.SilkS")
		)
		(fp_rect
			(start -0.508 0.9398)
			(end 0.508 -0.9398)
			(stroke
				(width 0)
				(type default)
			)
			(fill no)
			(layer "F.CrtYd")
		)
		(fp_rect
			(start -0.508 0.9398)
			(end 0.508 -0.9398)
			(stroke
				(width 0)
				(type default)
			)
			(fill no)
			(layer "F.Fab")
		)
		(pad "1" smd custom
			(at 0 -0.4445 180)
			(size 0.1397 0.1397)
			(layers "F.Cu" "F.Mask" "F.Paste")
			(net "IO_EXP3_HDD_FAULT_A0")
			(options
				(clearance outline)
				(anchor circle)
			)
			(primitives
				(gr_poly
					(pts
						(arc
							(start -0.1778 -0.2794)
							(mid -0.249642 -0.249642)
							(end -0.2794 -0.1778)
						)
						(arc
							(start -0.2794 0.1778)
							(mid -0.249642 0.249642)
							(end -0.1778 0.2794)
						)
						(arc
							(start 0.1778 0.2794)
							(mid 0.249642 0.249642)
							(end 0.2794 0.1778)
						)
						(arc
							(start 0.2794 -0.1778)
							(mid 0.249642 -0.249642)
							(end 0.1778 -0.2794)
						)
					)
					(width 0)
					(fill yes)
				)
			)
		)
		(pad "2" smd custom
			(at 0 0.4445 180)
			(size 0.1397 0.1397)
			(layers "F.Cu" "F.Mask" "F.Paste")
			(net "GND")
			(options
				(clearance outline)
				(anchor circle)
			)
			(primitives
				(gr_poly
					(pts
						(arc
							(start -0.1778 -0.2794)
							(mid -0.249642 -0.249642)
							(end -0.2794 -0.1778)
						)
						(arc
							(start -0.2794 0.1778)
							(mid -0.249642 0.249642)
							(end -0.1778 0.2794)
						)
						(arc
							(start 0.1778 0.2794)
							(mid 0.249642 0.249642)
							(end 0.2794 0.1778)
						)
						(arc
							(start 0.2794 -0.1778)
							(mid 0.249642 -0.249642)
							(end 0.1778 -0.2794)
						)
					)
					(width 0)
					(fill yes)
				)
			)
		)
	)
	(footprint ""
		(layer "F.Cu")
		(at 32.508952 -162.749992 -90)
		(property "Reference" "VIA46"
			(at 0 0 270)
			(layer "F.SilkS")
			(hide yes)
			(effects
				(font
					(size 1.27 1.27)
				)
			)
		)
		(property "Value" "100OHM-8L-1D6MM-L18L16-GP"
			(at -3.7211 -4.5085 270)
			(unlocked yes)
			(layer "F.Fab")
			(hide yes)
			(effects
				(font
					(size 1.016 1.016)
					(thickness 0.1524)
				)
			)
		)
		(property "Device Type" "VIA-PCIE-4P-394076"
			(at -3.7211 -6.0325 270)
			(unlocked yes)
			(layer "F.Fab")
			(hide yes)
			(effects
				(font
					(size 1.016 1.016)
					(thickness 0.1524)
				)
			)
		)
		(duplicate_pad_numbers_are_jumpers no)
		(fp_rect
			(start -1.9685 0.381)
			(end 1.9685 -0.381)
			(stroke
				(width 0)
				(type default)
			)
			(fill no)
			(layer "F.CrtYd")
		)
		(fp_rect
			(start -1.9685 0.381)
			(end 1.9685 -0.381)
			(stroke
				(width 0)
				(type default)
			)
			(fill no)
			(layer "F.Fab")
		)
		(pad "1" thru_hole circle
			(at -1.5875 0 270)
			(size 0.508 0.508)
			(drill 0.254)
			(layers "*.Cu" "*.Mask")
			(remove_unused_layers no)
			(net "GND")
			(clearance 0.127)
			(thermal_gap 0.127)
		)
		(pad "2" thru_hole circle
			(at -0.5715 0 270)
			(size 0.508 0.508)
			(drill 0.254)
			(layers "*.Cu" "*.Mask")
			(remove_unused_layers no)
			(net "PHY_DRV_A_TO_SCC_A_12_DP")
			(clearance 0.127)
			(thermal_gap 0.127)
		)
		(pad "3" thru_hole circle
			(at 0.5715 0 270)
			(size 0.508 0.508)
			(drill 0.254)
			(layers "*.Cu" "*.Mask")
			(remove_unused_layers no)
			(net "PHY_DRV_A_TO_SCC_A_12_DN")
			(clearance 0.127)
			(thermal_gap 0.127)
		)
		(pad "4" thru_hole circle
			(at 1.5875 0 270)
			(size 0.508 0.508)
			(drill 0.254)
			(layers "*.Cu" "*.Mask")
			(remove_unused_layers no)
			(net "GND")
			(clearance 0.127)
			(thermal_gap 0.127)
		)
	)
	(footprint ""
		(layer "F.Cu")
		(at 164.835078 -181.406038 90)
		(property "Reference" "R472"
			(at 0 0 90)
			(layer "F.SilkS")
			(hide yes)
			(effects
				(font
					(size 1.27 1.27)
				)
			)
		)
		(property "Value" "4K7R2J-2-GP"
			(at 0.064008 -3.993896 90)
			(unlocked yes)
			(layer "F.Fab")
			(hide yes)
			(effects
				(font
					(size 1.016 1.016)
					(thickness 0.1524)
				)
			)
		)
		(property "Device Type" "R402H16"
			(at 0.064008 -5.517896 90)
			(unlocked yes)
			(layer "F.Fab")
			(hide yes)
			(effects
				(font
					(size 1.016 1.016)
					(thickness 0.1524)
				)
			)
		)
		(duplicate_pad_numbers_are_jumpers no)
		(fp_line
			(start 0.508 -0.9398)
			(end -0.508 -0.9398)
			(stroke
				(width 0.1524)
				(type default)
			)
			(layer "F.SilkS")
		)
		(fp_line
			(start -0.508 -0.9398)
			(end -0.508 0.9398)
			(stroke
				(width 0.1524)
				(type default)
			)
			(layer "F.SilkS")
		)
		(fp_rect
			(start -0.508 0.9398)
			(end 0.508 -0.9398)
			(stroke
				(width 0)
				(type default)
			)
			(fill no)
			(layer "F.CrtYd")
		)
		(fp_rect
			(start -0.508 0.9398)
			(end 0.508 -0.9398)
			(stroke
				(width 0)
				(type default)
			)
			(fill no)
			(layer "F.Fab")
		)
		(pad "1" smd custom
			(at 0 -0.4445 90)
			(size 0.1397 0.1397)
			(layers "F.Cu" "F.Mask" "F.Paste")
			(net "DRIVE_A_5_ACT")
			(options
				(clearance outline)
				(anchor circle)
			)
			(primitives
				(gr_poly
					(pts
						(arc
							(start -0.1778 -0.2794)
							(mid -0.249642 -0.249642)
							(end -0.2794 -0.1778)
						)
						(arc
							(start -0.2794 0.1778)
							(mid -0.249642 0.249642)
							(end -0.1778 0.2794)
						)
						(arc
							(start 0.1778 0.2794)
							(mid 0.249642 0.249642)
							(end 0.2794 0.1778)
						)
						(arc
							(start 0.2794 -0.1778)
							(mid 0.249642 -0.249642)
							(end 0.1778 -0.2794)
						)
					)
					(width 0)
					(fill yes)
				)
			)
		)
		(pad "2" smd custom
			(at 0 0.4445 90)
			(size 0.1397 0.1397)
			(layers "F.Cu" "F.Mask" "F.Paste")
			(net "GND")
			(options
				(clearance outline)
				(anchor circle)
			)
			(primitives
				(gr_poly
					(pts
						(arc
							(start -0.1778 -0.2794)
							(mid -0.249642 -0.249642)
							(end -0.2794 -0.1778)
						)
						(arc
							(start -0.2794 0.1778)
							(mid -0.249642 0.249642)
							(end -0.1778 0.2794)
						)
						(arc
							(start 0.1778 0.2794)
							(mid 0.249642 0.249642)
							(end 0.2794 0.1778)
						)
						(arc
							(start 0.2794 -0.1778)
							(mid 0.249642 -0.249642)
							(end 0.1778 -0.2794)
						)
					)
					(width 0)
					(fill yes)
				)
			)
		)
	)
	(footprint ""
		(layer "F.Cu")
		(at 158.663386 -159.219392 90)
		(property "Reference" "C246"
			(at 0 0 90)
			(layer "F.SilkS")
			(hide yes)
			(effects
				(font
					(size 1.27 1.27)
				)
			)
		)
		(property "Value" "SCD01U16V1KX-GP"
			(at -2.8321 -1.7399 90)
			(unlocked yes)
			(layer "F.Fab")
			(hide yes)
			(effects
				(font
					(size 1.016 1.016)
					(thickness 0.1524)
				)
			)
		)
		(property "Device Type" "C0201H13"
			(at -2.8321 -3.2639 90)
			(unlocked yes)
			(layer "F.Fab")
			(hide yes)
			(effects
				(font
					(size 1.016 1.016)
					(thickness 0.1524)
				)
			)
		)
		(duplicate_pad_numbers_are_jumpers no)
		(fp_rect
			(start -0.2794 0.6477)
			(end 0.2794 -0.6477)
			(stroke
				(width 0)
				(type default)
			)
			(fill no)
			(layer "F.CrtYd")
		)
		(fp_rect
			(start -0.2794 0.6477)
			(end 0.2794 -0.6477)
			(stroke
				(width 0)
				(type default)
			)
			(fill no)
			(layer "F.Fab")
		)
		(pad "1" smd custom
			(at 0 -0.2794 90)
			(size 0.0762 0.0762)
			(layers "F.Cu" "F.Mask" "F.Paste")
			(net "SAS_HDD_RX_N16")
			(options
				(clearance outline)
				(anchor circle)
			)
			(primitives
				(gr_poly
					(pts
						(arc
							(start 0.1524 -0.127)
							(mid 0.137521 -0.162921)
							(end 0.1016 -0.1778)
						)
						(arc
							(start -0.1016 -0.1778)
							(mid -0.137521 -0.162921)
							(end -0.1524 -0.127)
						)
						(arc
							(start -0.1524 0.127)
							(mid -0.137521 0.162921)
							(end -0.1016 0.1778)
						)
						(arc
							(start 0.1016 0.1778)
							(mid 0.137521 0.162921)
							(end 0.1524 0.127)
						)
					)
					(width 0)
					(fill yes)
				)
			)
		)
		(pad "2" smd custom
			(at 0 0.2794 90)
			(size 0.0762 0.0762)
			(layers "F.Cu" "F.Mask" "F.Paste")
			(net "PHY_SCC_A_TO_DRV_A_16_DN")
			(options
				(clearance outline)
				(anchor circle)
			)
			(primitives
				(gr_poly
					(pts
						(arc
							(start 0.1524 -0.127)
							(mid 0.137521 -0.162921)
							(end 0.1016 -0.1778)
						)
						(arc
							(start -0.1016 -0.1778)
							(mid -0.137521 -0.162921)
							(end -0.1524 -0.127)
						)
						(arc
							(start -0.1524 0.127)
							(mid -0.137521 0.162921)
							(end -0.1016 0.1778)
						)
						(arc
							(start 0.1016 0.1778)
							(mid 0.137521 0.162921)
							(end 0.1524 0.127)
						)
					)
					(width 0)
					(fill yes)
				)
			)
		)
	)
	(footprint ""
		(layer "F.Cu")
		(at 335.788 -42.585894 180)
		(property "Reference" "R831"
			(at 0 0 180)
			(layer "F.SilkS")
			(hide yes)
			(effects
				(font
					(size 1.27 1.27)
				)
			)
		)
		(property "Value" "0R2J-2-GP"
			(at 0.064008 -3.993896 180)
			(unlocked yes)
			(layer "F.Fab")
			(hide yes)
			(effects
				(font
					(size 1.016 1.016)
					(thickness 0.1524)
				)
			)
		)
		(property "Device Type" "R402H16"
			(at 0.064008 -5.517896 180)
			(unlocked yes)
			(layer "F.Fab")
			(hide yes)
			(effects
				(font
					(size 1.016 1.016)
					(thickness 0.1524)
				)
			)
		)
		(duplicate_pad_numbers_are_jumpers no)
		(fp_line
			(start 0.508 -0.9398)
			(end -0.508 -0.9398)
			(stroke
				(width 0.1524)
				(type default)
			)
			(layer "F.SilkS")
		)
		(fp_line
			(start -0.508 -0.9398)
			(end -0.508 0.9398)
			(stroke
				(width 0.1524)
				(type default)
			)
			(layer "F.SilkS")
		)
		(fp_rect
			(start -0.508 0.9398)
			(end 0.508 -0.9398)
			(stroke
				(width 0)
				(type default)
			)
			(fill no)
			(layer "F.CrtYd")
		)
		(fp_rect
			(start -0.508 0.9398)
			(end 0.508 -0.9398)
			(stroke
				(width 0)
				(type default)
			)
			(fill no)
			(layer "F.Fab")
		)
		(pad "1" smd custom
			(at 0 -0.4445 180)
			(size 0.1397 0.1397)
			(layers "F.Cu" "F.Mask" "F.Paste")
			(net "DRIVE_A_30_PWR")
			(options
				(clearance outline)
				(anchor circle)
			)
			(primitives
				(gr_poly
					(pts
						(arc
							(start -0.1778 -0.2794)
							(mid -0.249642 -0.249642)
							(end -0.2794 -0.1778)
						)
						(arc
							(start -0.2794 0.1778)
							(mid -0.249642 0.249642)
							(end -0.1778 0.2794)
						)
						(arc
							(start 0.1778 0.2794)
							(mid 0.249642 0.249642)
							(end 0.2794 0.1778)
						)
						(arc
							(start 0.2794 -0.1778)
							(mid 0.249642 -0.249642)
							(end 0.1778 -0.2794)
						)
					)
					(width 0)
					(fill yes)
				)
			)
		)
		(pad "2" smd custom
			(at 0 0.4445 180)
			(size 0.1397 0.1397)
			(layers "F.Cu" "F.Mask" "F.Paste")
			(net "SW_PWR_R_HDD30")
			(options
				(clearance outline)
				(anchor circle)
			)
			(primitives
				(gr_poly
					(pts
						(arc
							(start -0.1778 -0.2794)
							(mid -0.249642 -0.249642)
							(end -0.2794 -0.1778)
						)
						(arc
							(start -0.2794 0.1778)
							(mid -0.249642 0.249642)
							(end -0.1778 0.2794)
						)
						(arc
							(start 0.1778 0.2794)
							(mid 0.249642 0.249642)
							(end 0.2794 0.1778)
						)
						(arc
							(start 0.2794 -0.1778)
							(mid 0.249642 -0.249642)
							(end 0.1778 -0.2794)
						)
					)
					(width 0)
					(fill yes)
				)
			)
		)
	)
)
